# BASEBOARD_FAB2 (Tioga Pass) — schematic netlist excerpt (pin names and nets, part order shuffled) for the footprints in the layout excerpt that follows; sources: Cadence DE-HDL packaged netlist, KiCad conversion of Wiwynn_Tioga_Pass_MB.brd

C7C7  SC22U16V5MX-4-GP  20%  pkg SMD-BCG5  page 212 : \1\ = VR_FET_SW_P12V_STBY_PVCCIO_CPU0 ; \2\ = GND
C7F17  CAP_A  0.1UF 16V 10% X7R  pkg 0402V  page 215 : A = VR_PVDDQ_ABC_VDD ; B = GND
R7C2  RES  0.0 5% CHIP  pkg 0402  page 114 : A = CLK_100M_BMC_PE_R_DN ; B = CLK_100M_BMC_PE_DN

(kicad_pcb
	(version 20260206)
	(generator "pcbnew")
	(generator_version "10.0")
	(general
		(thickness 1.6)
		(legacy_teardrops no)
	)
	(paper "A4")
	(title_block
		(title "Wiwynn_Tioga_Pass_MB.brd")
		(comment 1 "Tioga Pass / footprints 1332-1334 of 4770")
	)
	(layers
		(0 "F.Cu" signal "TOP")
		(4 "In1.Cu" signal "L2GND")
		(6 "In2.Cu" signal "L3")
		(8 "In3.Cu" signal "L4GND")
		(10 "In4.Cu" signal "L5")
		(12 "In5.Cu" signal "L6GND")
		(14 "In6.Cu" signal "L7VCC")
		(16 "In7.Cu" signal "L8VCC")
		(18 "In8.Cu" signal "L9GND")
		(20 "In9.Cu" signal "L10")
		(22 "In10.Cu" signal "L11GND")
		(24 "In11.Cu" signal "L12")
		(26 "In12.Cu" signal "L13GND")
		(2 "B.Cu" signal "BOTTOM")
		(9 "F.Adhes" user "F.Adhesive")
		(11 "B.Adhes" user "B.Adhesive")
		(13 "F.Paste" user "Package Geometry/Pastemask Top")
		(15 "B.Paste" user "Package Geometry/Pastemask Bottom")
		(5 "F.SilkS" user "Ref Des/Silkscreen Top")
		(7 "B.SilkS" user "Ref Des/Silkscreen Bottom")
		(1 "F.Mask" user "Board Geometry/Soldermask Top")
		(3 "B.Mask" user "Board Geometry/Soldermask Bottom")
		(17 "Dwgs.User" user "User.Drawings")
		(19 "Cmts.User" user "User.Comments")
		(21 "Eco1.User" user "User.Eco1")
		(23 "Eco2.User" user "User.Eco2")
		(25 "Edge.Cuts" user "Board Geometry/Outline")
		(27 "Margin" user)
		(31 "F.CrtYd" user "Package Geometry/Place Bound Top")
		(29 "B.CrtYd" user "Package Geometry/Place Bound Bottom")
		(35 "F.Fab" user "Ref Des/Assembly Top")
		(33 "B.Fab" user "Ref Des/Assembly Bottom")
	)
	(footprint ""
		(layer "F.Cu")
		(at 346.456 -104.267 180)
		(property "Reference" "C7C7"
			(at 0 0 180)
			(layer "F.SilkS")
			(hide yes)
			(effects
				(font
					(size 1.27 1.27)
				)
			)
		)
		(property "Value" "*"
			(at -0.0762 -6.2357 180)
			(unlocked yes)
			(layer "F.Fab")
			(hide yes)
			(effects
				(font
					(size 1.27 1.016)
					(thickness 0.1524)
				)
			)
		)
		(property "Device Type" "SC22U16V5MX-4-GP_SMD-BCG5-SC22A"
			(at -0.0762 -8.2677 180)
			(unlocked yes)
			(layer "F.Fab")
			(hide yes)
			(effects
				(font
					(size 1.27 1.016)
					(thickness 0.1524)
				)
			)
		)
		(duplicate_pad_numbers_are_jumpers no)
		(fp_line
			(start 0.635 0)
			(end -0.635 0)
			(stroke
				(width 0.508)
				(type default)
			)
			(layer "F.SilkS")
		)
		(fp_rect
			(start -0.9652 1.778)
			(end 0.9652 -1.778)
			(stroke
				(width 0)
				(type default)
			)
			(fill no)
			(layer "F.CrtYd")
		)
		(fp_poly
			(pts
				(xy -0.9652 -1.778) (xy 0.9652 -1.778) (xy 0.9652 1.778) (xy -0.9652 1.778)
			)
			(stroke
				(width 0)
				(type default)
			)
			(fill no)
			(layer "F.Fab")
		)
		(pad "1" smd rect
			(at 0 -0.9652 180)
			(size 1.397 1.143)
			(layers "F.Cu" "F.Mask" "F.Paste")
			(net "VR_FET_SW_P12V_STBY_PVCCIO_CPU0")
		)
		(pad "2" smd rect
			(at 0 0.9652 180)
			(size 1.397 1.143)
			(layers "F.Cu" "F.Mask" "F.Paste")
			(net "GND")
		)
	)
	(footprint ""
		(layer "F.Cu")
		(at 349.123 -17.78 180)
		(property "Reference" "C7F17"
			(at 0 0 180)
			(layer "F.SilkS")
			(hide yes)
			(effects
				(font
					(size 1.27 1.27)
				)
			)
		)
		(property "Value" ""
			(at 0 0 180)
			(layer "F.Fab")
			(effects
				(font
					(size 1.27 1.27)
				)
			)
		)
		(duplicate_pad_numbers_are_jumpers no)
		(fp_rect
			(start 0.3048 -0.1016)
			(end -0.3048 0.9906)
			(stroke
				(width 0)
				(type default)
			)
			(fill no)
			(layer "F.CrtYd")
		)
		(fp_line
			(start 0.3048 0.9906)
			(end 0.3048 -0.1016)
			(stroke
				(width 0.1)
				(type default)
			)
			(layer "F.Fab")
		)
		(fp_line
			(start 0.3048 -0.1016)
			(end -0.3048 -0.1016)
			(stroke
				(width 0.1)
				(type default)
			)
			(layer "F.Fab")
		)
		(fp_line
			(start -0.3048 0.9906)
			(end 0.3048 0.9906)
			(stroke
				(width 0.1)
				(type default)
			)
			(layer "F.Fab")
		)
		(fp_line
			(start -0.3048 -0.1016)
			(end -0.3048 0.9906)
			(stroke
				(width 0.1)
				(type default)
			)
			(layer "F.Fab")
		)
		(pad "1" smd rect
			(at 0 0 180)
			(size 0.508 0.508)
			(layers "F.Cu" "F.Mask" "F.Paste")
			(net "VR_PVDDQ_ABC_VDD")
		)
		(pad "2" smd rect
			(at 0 0.889 180)
			(size 0.508 0.508)
			(layers "F.Cu" "F.Mask" "F.Paste")
			(net "GND")
		)
		(zone
			(layer "F.Cu")
			(hatch none 0.5)
			(connect_pads
				(clearance 0)
			)
			(min_thickness 0.25)
			(keepout
				(tracks not_allowed)
				(vias allowed)
				(pads allowed)
				(copperpour not_allowed)
				(footprints allowed)
			)
			(placement
				(enabled no)
				(sheetname "")
			)
			(fill
				(thermal_gap 0.5)
				(thermal_bridge_width 0.5)
				(island_removal_mode 0)
			)
			(polygon
				(pts
					(xy 348.869 -18.034) (xy 349.377 -18.034) (xy 349.377 -18.415) (xy 348.869 -18.415)
				)
			)
		)
		(zone
			(layer "F.Cu")
			(hatch none 0.5)
			(connect_pads
				(clearance 0)
			)
			(min_thickness 0.25)
			(keepout
				(tracks allowed)
				(vias not_allowed)
				(pads allowed)
				(copperpour not_allowed)
				(footprints allowed)
			)
			(placement
				(enabled no)
				(sheetname "")
			)
			(fill
				(thermal_gap 0.5)
				(thermal_bridge_width 0.5)
				(island_removal_mode 0)
			)
			(polygon
				(pts
					(xy 348.869 -18.034) (xy 349.377 -18.034) (xy 349.377 -18.415) (xy 348.869 -18.415)
				)
			)
		)
	)
	(footprint ""
		(layer "F.Cu")
		(at 369.333526 -105.198164 90)
		(property "Reference" "R7C2"
			(at 0 0 90)
			(layer "F.SilkS")
			(hide yes)
			(effects
				(font
					(size 1.27 1.27)
				)
			)
		)
		(property "Value" ""
			(at 0 0 90)
			(layer "F.Fab")
			(effects
				(font
					(size 1.27 1.27)
				)
			)
		)
		(duplicate_pad_numbers_are_jumpers no)
		(fp_poly
			(pts
				(xy -0.2794 -0.1016) (xy 0.2794 -0.1016) (xy 0.2794 0.9906) (xy -0.2794 0.9906)
			)
			(stroke
				(width 0)
				(type default)
			)
			(fill no)
			(layer "F.CrtYd")
		)
		(fp_line
			(start 0.2794 -0.1016)
			(end -0.2794 -0.1016)
			(stroke
				(width 0.1)
				(type default)
			)
			(layer "F.Fab")
		)
		(fp_line
			(start -0.2794 -0.1016)
			(end -0.2794 0.9906)
			(stroke
				(width 0.1)
				(type default)
			)
			(layer "F.Fab")
		)
		(fp_line
			(start 0.2794 0.9906)
			(end 0.2794 -0.1016)
			(stroke
				(width 0.1)
				(type default)
			)
			(layer "F.Fab")
		)
		(fp_line
			(start -0.2794 0.9906)
			(end 0.2794 0.9906)
			(stroke
				(width 0.1)
				(type default)
			)
			(layer "F.Fab")
		)
		(pad "1" smd rect
			(at 0 0 90)
			(size 0.508 0.508)
			(layers "F.Cu" "F.Mask" "F.Paste")
			(net "CLK_100M_BMC_PE_R_DN")
		)
		(pad "2" smd rect
			(at 0 0.889 90)
			(size 0.508 0.508)
			(layers "F.Cu" "F.Mask" "F.Paste")
			(net "CLK_100M_BMC_PE_DN")
		)
		(zone
			(layer "F.Cu")
			(hatch none 0.5)
			(connect_pads
				(clearance 0)
			)
			(min_thickness 0.25)
			(keepout
				(tracks allowed)
				(vias not_allowed)
				(pads allowed)
				(copperpour not_allowed)
				(footprints allowed)
			)
			(placement
				(enabled no)
				(sheetname "")
			)
			(fill
				(thermal_gap 0.5)
				(thermal_bridge_width 0.5)
				(island_removal_mode 0)
			)
			(polygon
				(pts
					(xy 369.587526 -104.944164) (xy 369.587526 -105.452164) (xy 369.968526 -105.452164) (xy 369.968526 -104.944164)
				)
			)
		)
		(zone
			(layer "F.Cu")
			(hatch none 0.5)
			(connect_pads
				(clearance 0)
			)
			(min_thickness 0.25)
			(keepout
				(tracks not_allowed)
				(vias allowed)
				(pads allowed)
				(copperpour not_allowed)
				(footprints allowed)
			)
			(placement
				(enabled no)
				(sheetname "")
			)
			(fill
				(thermal_gap 0.5)
				(thermal_bridge_width 0.5)
				(island_removal_mode 0)
			)
			(polygon
				(pts
					(xy 369.968526 -104.944164) (xy 369.968526 -105.452164) (xy 369.587526 -105.452164) (xy 369.587526 -104.944164)
				)
			)
		)
	)
)
